FILE_TYPE = CONNECTIVITY;
{Allegro Design Entry HDL 17.2-2016 S081 (4005846) 1/11/2022}
"PAGE_NUMBER" = 40;
0"NC";
1"GND\g";
2"GND\g";
3"GND\g";
4"GND\g";
5"GND\g";
6"GND\g";
%"UNIVERSAL_GND"
"1","(-3675,-725)","0","logical_power","I1";
;
CDS_LIB"logical_power"
HDL_POWER"GND";
"A"6;
%"SOCKET4677_AZIF0045P001C01CS"
"34","(-2225,1800)","0","pure_quanta","I10";
;
PART_NUMBER"DGA^7000023"
PART_TYPE"SMLF"
MATERIAL"IO"
VALUE"SOCKET4677_AZIF0045-P001C01CS"
$LOCATION"U2"
CDS_LIB"pure_quanta"
NEEDS_NO_SIZE"TRUE"
CDS_LMAN_SYM_OUTLINE"-1050,2150,1050,-2100"
CDS_LOCATION"U2"
$SEC"34"
CDS_SEC"34";
"VSS723"
$PN"DB91"5;
"VSS724"
$PN"DC1"5;
"VSS725"
$PN"DC13"5;
"VSS726"
$PN"DC21"5;
"VSS735"
$PN"DC52"5;
"VSS738"
$PN"DC58"5;
"VSS739"
$PN"DC64"5;
"VSS747"
$PN"DD12"5;
"VSS748"
$PN"DD16"5;
"VSS753"
$PN"DD49"5;
"VSS776"
$PN"DE39"5;
"VSS791"
$PN"DE70"5;
"VSS798"
$PN"DF12"5;
"VSS799"
$PN"DF16"5;
"VSS802"
$PN"DF49"5;
"VSS806"
$PN"DF91"5;
"VSS807"
$PN"DG1"5;
"VSS808"
$PN"DG13"5;
"VSS809"
$PN"DG21"5;
"VSS817"
$PN"DG52"5;
"VSS820"
$PN"DG58"5;
"VSS821"
$PN"DG64"5;
"VSS829"
$PN"DH16"6;
"VSS830"
$PN"DH20"6;
"VSS832"
$PN"DH26"6;
"VSS835"
$PN"DH34"6;
"VSS839"
$PN"DH44"6;
"VSS841"
$PN"DH51"6;
"VSS842"
$PN"DH53"6;
"VSS844"
$PN"DH59"6;
"VSS845"
$PN"DH63"6;
"VSS847"
$PN"DH69"6;
"VSS849"
$PN"DH75"6;
"VSS857"
$PN"DJ25"6;
"VSS861"
$PN"DJ35"6;
"VSS867"
$PN"DJ54"6;
"VSS870"
$PN"DJ62"6;
"VSS872"
$PN"DJ68"6;
"VSS880"
$PN"DK12"6;
"VSS882"
$PN"DK18"6;
"VSS883"
$PN"DK24"6;
"VSS887"
$PN"DK42"6;
"VSS890"
$PN"DK55"6;
"VSS893"
$PN"DK61"6;
"VSS894"
$PN"DK67"6;
"VSS903"
$PN"DL1"6;
"VSS904"
$PN"DL13"6;
"VSS905"
$PN"DL17"6;
"VSS908"
$PN"DL5"6;
"VSS909"
$PN"DL52"6;
"VSS949"
$PN"DC27"5;
"VSS950"
$PN"DC33"5;
"VSS951"
$PN"DC39"5;
"VSS952"
$PN"DC45"5;
"VSS953"
$PN"DC5"5;
"VSS954"
$PN"DC70"5;
"VSS956"
$PN"DC76"5;
"VSS958"
$PN"DC78"5;
"VSS960"
$PN"DC80"5;
"VSS961"
$PN"DC84"5;
"VSS962"
$PN"DC88"5;
"VSS963"
$PN"DC9"5;
"VSS964"
$PN"DD4"5;
"VSS965"
$PN"DD79"5;
"VSS967"
$PN"DD8"5;
"VSS970"
$PN"DE17"5;
"VSS971"
$PN"DE19"5;
"VSS972"
$PN"DE21"5;
"VSS974"
$PN"DE23"5;
"VSS975"
$PN"DE25"5;
"VSS977"
$PN"DE27"5;
"VSS978"
$PN"DE29"5;
"VSS981"
$PN"DE31"5;
"VSS982"
$PN"DE33"5;
"VSS983"
$PN"DE35"5;
"VSS984"
$PN"DE37"5;
"VSS986"
$PN"DE41"5;
"VSS987"
$PN"DE43"5;
"VSS988"
$PN"DE45"5;
"VSS989"
$PN"DE48"5;
"VSS991"
$PN"DE50"5;
"VSS992"
$PN"DE52"5;
"VSS994"
$PN"DE54"5;
"VSS995"
$PN"DE56"5;
"VSS996"
$PN"DE58"5;
"VSS997"
$PN"DE60"5;
"VSS999"
$PN"DE62"5;
"VSS1001"
$PN"DE64"5;
"VSS1004"
$PN"DE66"5;
"VSS1007"
$PN"DE68"5;
"VSS1008"
$PN"DE72"5;
"VSS1009"
$PN"DE74"5;
"VSS1010"
$PN"DE76"5;
"VSS1011"
$PN"DE82"5;
"VSS1012"
$PN"DE84"5;
"VSS1015"
$PN"DE88"5;
"VSS1017"
$PN"DF4"5;
"VSS1018"
$PN"DF79"5;
"VSS1019"
$PN"DF8"5;
"VSS1020"
$PN"DF87"5;
"VSS1022"
$PN"DG27"5;
"VSS1024"
$PN"DG33"5;
"VSS1027"
$PN"DG39"5;
"VSS1030"
$PN"DG45"5;
"VSS1031"
$PN"DG5"5;
"VSS1032"
$PN"DG70"5;
"VSS1033"
$PN"DG76"5;
"VSS1034"
$PN"DG80"6;
"VSS1035"
$PN"DG84"6;
"VSS1037"
$PN"DG88"6;
"VSS1038"
$PN"DG9"5;
"VSS1039"
$PN"DH12"6;
"VSS1040"
$PN"DH22"6;
"VSS1041"
$PN"DH28"6;
"VSS1042"
$PN"DH32"6;
"VSS1043"
$PN"DH38"6;
"VSS1044"
$PN"DH4"6;
"VSS1045"
$PN"DH40"6;
"VSS1046"
$PN"DH47"6;
"VSS1049"
$PN"DH57"6;
"VSS1053"
$PN"DH65"6;
"VSS1055"
$PN"DH71"6;
"VSS1056"
$PN"DH77"6;
"VSS1057"
$PN"DH8"6;
"VSS1058"
$PN"DH85"6;
"VSS1061"
$PN"DJ19"6;
"VSS1062"
$PN"DJ23"6;
"VSS1065"
$PN"DJ29"6;
"VSS1066"
$PN"DJ31"6;
"VSS1067"
$PN"DJ37"6;
"VSS1068"
$PN"DJ41"6;
"VSS1069"
$PN"DJ43"6;
"VSS1070"
$PN"DJ48"6;
"VSS1071"
$PN"DJ50"6;
"VSS1072"
$PN"DJ56"6;
"VSS1073"
$PN"DJ60"6;
"VSS1074"
$PN"DJ66"6;
"VSS1075"
$PN"DJ72"6;
"VSS1076"
$PN"DJ74"6;
"VSS1078"
$PN"DJ80"6;
"VSS1079"
$PN"DJ82"6;
"VSS1080"
$PN"DJ84"6;
"VSS1081"
$PN"DJ88"6;
"VSS1082"
$PN"DK16"6;
"VSS1083"
$PN"DK30"6;
"VSS1084"
$PN"DK36"6;
"VSS1085"
$PN"DK4"6;
"VSS1086"
$PN"DK49"6;
"VSS1087"
$PN"DK73"6;
"VSS1088"
$PN"DK77"6;
"VSS1089"
$PN"DK79"6;
"VSS1090"
$PN"DK8"6;
"VSS1091"
$PN"DK81"6;
"VSS1092"
$PN"DK83"6;
"VSS1093"
$PN"DK87"6;
"VSS1094"
$PN"DK91"6;
"VSS1095"
$PN"DL39"6;
"VSS1096"
$PN"DL84"6;
"VSS1098"
$PN"DL88"6;
"VSS1099"
$PN"DL9"6;
%"SOCKET4677_AZIF0045P001C01CS"
"35","(825,1800)","0","pure_quanta","I11";
;
PART_NUMBER"DGA^7000023"
PART_TYPE"SMLF"
MATERIAL"IO"
VALUE"SOCKET4677_AZIF0045-P001C01CS"
$LOCATION"U2"
CDS_LIB"pure_quanta"
NEEDS_NO_SIZE"TRUE"
CDS_LMAN_SYM_OUTLINE"-1050,2150,1050,-2100"
CDS_LOCATION"U2"
$SEC"35"
CDS_SEC"35";
"VSS436"
$PN"CM16"3;
"VSS438"
$PN"CM22"3;
"VSS471"
$PN"CN76"3;
"VSS478"
$PN"CP16"3;
"VSS493"
$PN"CP79"3;
"VSS514"
$PN"CR78"3;
"VSS521"
$PN"CT16"3;
"VSS526"
$PN"CT4"3;
"VSS534"
$PN"CT8"3;
"VSS537"
$PN"CT89"3;
"VSS544"
$PN"CU25"3;
"VSS553"
$PN"CU72"3;
"VSS554"
$PN"CU78"3;
"VSS558"
$PN"CV16"4;
"VSS562"
$PN"CV26"4;
"VSS571"
$PN"CV79"4;
"VSS583"
$PN"CW33"4;
"VSS595"
$PN"CW70"4;
"VSS611"
$PN"CY4"4;
"VSS679"
$PN"DA43"4;
"VSS690"
$PN"DA68"4;
"VSS699"
$PN"DB16"4;
"VSS700"
$PN"DB20"4;
"VSS702"
$PN"DB26"4;
"VSS705"
$PN"DB34"4;
"VSS709"
$PN"DB44"4;
"VSS711"
$PN"DB51"4;
"VSS712"
$PN"DB53"4;
"VSS714"
$PN"DB59"4;
"VSS715"
$PN"DB63"4;
"VSS717"
$PN"DB69"4;
"VSS719"
$PN"DB75"4;
"VSS744"
$PN"CK63"3;
"VSS745"
$PN"CK69"3;
"VSS749"
$PN"CK81"3;
"VSS750"
$PN"CL1"3;
"VSS751"
$PN"CL13"3;
"VSS752"
$PN"CL17"3;
"VSS754"
$PN"CL5"3;
"VSS755"
$PN"CL62"3;
"VSS756"
$PN"CL74"3;
"VSS757"
$PN"CL78"3;
"VSS758"
$PN"CL80"3;
"VSS759"
$PN"CL82"3;
"VSS760"
$PN"CL9"3;
"VSS761"
$PN"CM12"3;
"VSS762"
$PN"CM20"3;
"VSS763"
$PN"CM24"3;
"VSS764"
$PN"CM4"3;
"VSS765"
$PN"CM61"3;
"VSS766"
$PN"CM65"3;
"VSS767"
$PN"CM67"3;
"VSS768"
$PN"CM79"3;
"VSS769"
$PN"CM8"3;
"VSS770"
$PN"CM81"3;
"VSS771"
$PN"CM83"3;
"VSS772"
$PN"CM85"3;
"VSS773"
$PN"CN68"3;
"VSS774"
$PN"CN70"3;
"VSS775"
$PN"CN72"3;
"VSS777"
$PN"CN74"3;
"VSS778"
$PN"CN84"3;
"VSS779"
$PN"CN86"3;
"VSS780"
$PN"CP12"3;
"VSS781"
$PN"CP18"3;
"VSS782"
$PN"CP4"3;
"VSS783"
$PN"CP75"3;
"VSS784"
$PN"CP77"3;
"VSS785"
$PN"CP8"3;
"VSS786"
$PN"CP83"3;
"VSS787"
$PN"CP87"3;
"VSS788"
$PN"CP91"3;
"VSS789"
$PN"CR1"3;
"VSS790"
$PN"CR11"3;
"VSS792"
$PN"CR13"3;
"VSS793"
$PN"CR17"3;
"VSS794"
$PN"CR5"3;
"VSS795"
$PN"CR62"3;
"VSS796"
$PN"CR64"3;
"VSS797"
$PN"CR84"3;
"VSS800"
$PN"CR88"3;
"VSS801"
$PN"CR9"3;
"VSS803"
$PN"CR90"3;
"VSS804"
$PN"CT10"3;
"VSS805"
$PN"CT12"3;
"VSS810"
$PN"CT69"3;
"VSS811"
$PN"CT73"3;
"VSS812"
$PN"CT81"3;
"VSS813"
$PN"CU19"3;
"VSS814"
$PN"CU21"3;
"VSS815"
$PN"CU23"3;
"VSS816"
$PN"CU60"3;
"VSS818"
$PN"CU66"3;
"VSS819"
$PN"CU68"3;
"VSS822"
$PN"CU84"3;
"VSS823"
$PN"CU88"3;
"VSS824"
$PN"CV12"3;
"VSS825"
$PN"CV4"3;
"VSS826"
$PN"CV75"4;
"VSS827"
$PN"CV8"3;
"VSS828"
$PN"CV83"4;
"VSS831"
$PN"CV87"4;
"VSS833"
$PN"CV91"4;
"VSS834"
$PN"CW1"4;
"VSS836"
$PN"CW13"4;
"VSS837"
$PN"CW17"4;
"VSS838"
$PN"CW5"4;
"VSS840"
$PN"CW72"4;
"VSS843"
$PN"CW78"4;
"VSS846"
$PN"CW84"4;
"VSS848"
$PN"CW88"4;
"VSS850"
$PN"CW9"4;
"VSS851"
$PN"CY12"4;
"VSS852"
$PN"CY16"4;
"VSS853"
$PN"CY18"4;
"VSS854"
$PN"CY26"4;
"VSS855"
$PN"CY30"4;
"VSS856"
$PN"CY63"4;
"VSS858"
$PN"CY73"4;
"VSS859"
$PN"CY77"4;
"VSS860"
$PN"CY8"4;
"VSS862"
$PN"CY81"4;
"VSS863"
$PN"CY83"4;
"VSS910"
$PN"DA19"4;
"VSS911"
$PN"DA23"4;
"VSS912"
$PN"DA25"4;
"VSS913"
$PN"DA29"4;
"VSS914"
$PN"DA31"4;
"VSS915"
$PN"DA33"4;
"VSS916"
$PN"DA35"4;
"VSS917"
$PN"DA37"4;
"VSS918"
$PN"DA41"4;
"VSS919"
$PN"DA48"4;
"VSS920"
$PN"DA50"4;
"VSS921"
$PN"DA54"4;
"VSS922"
$PN"DA56"4;
"VSS923"
$PN"DA58"4;
"VSS924"
$PN"DA60"4;
"VSS925"
$PN"DA62"4;
"VSS926"
$PN"DA66"4;
"VSS927"
$PN"DA72"4;
"VSS928"
$PN"DA74"4;
"VSS929"
$PN"DA80"4;
"VSS930"
$PN"DA82"4;
"VSS931"
$PN"DA84"4;
"VSS932"
$PN"DA88"4;
"VSS933"
$PN"DB12"4;
"VSS935"
$PN"DB22"4;
"VSS936"
$PN"DB28"4;
"VSS937"
$PN"DB32"4;
"VSS938"
$PN"DB38"4;
"VSS939"
$PN"DB4"4;
"VSS940"
$PN"DB40"4;
"VSS941"
$PN"DB47"4;
"VSS942"
$PN"DB57"4;
"VSS943"
$PN"DB65"4;
"VSS944"
$PN"DB71"4;
"VSS946"
$PN"DB77"4;
"VSS947"
$PN"DB8"4;
"VSS948"
$PN"DB87"4;
%"SOCKET4677_AZIF0045P001C01CS"
"36","(3850,1800)","0","pure_quanta","I12";
;
PART_NUMBER"DGA^7000023"
PART_TYPE"SMLF"
MATERIAL"IO"
VALUE"SOCKET4677_AZIF0045-P001C01CS"
$LOCATION"U2"
CDS_LIB"pure_quanta"
NEEDS_NO_SIZE"TRUE"
CDS_LMAN_SYM_OUTLINE"-1050,2150,1050,-2100"
CDS_LOCATION"U2"
$SEC"36"
CDS_SEC"36";
"VSS383"
$PN"CJ76"2;
"VSS396"
$PN"CK4"2;
"VSS542"
$PN"BR35"1;
"VSS543"
$PN"BR37"1;
"VSS545"
$PN"BR39"1;
"VSS546"
$PN"BR41"1;
"VSS547"
$PN"BR43"1;
"VSS548"
$PN"BR45"1;
"VSS549"
$PN"BR48"1;
"VSS550"
$PN"BR50"1;
"VSS551"
$PN"BR52"1;
"VSS552"
$PN"BR54"1;
"VSS555"
$PN"BR56"1;
"VSS556"
$PN"BR58"1;
"VSS557"
$PN"BR64"1;
"VSS559"
$PN"BR66"1;
"VSS560"
$PN"BR68"1;
"VSS561"
$PN"BR70"1;
"VSS563"
$PN"BR72"1;
"VSS564"
$PN"BR74"1;
"VSS565"
$PN"BR76"1;
"VSS566"
$PN"BR80"1;
"VSS567"
$PN"BR82"1;
"VSS568"
$PN"BR84"1;
"VSS569"
$PN"BR86"1;
"VSS570"
$PN"BR88"1;
"VSS573"
$PN"BR90"1;
"VSS574"
$PN"BT12"1;
"VSS575"
$PN"BT16"1;
"VSS576"
$PN"BT20"1;
"VSS577"
$PN"BT4"1;
"VSS578"
$PN"BT8"1;
"VSS579"
$PN"BU15"1;
"VSS580"
$PN"BU19"1;
"VSS581"
$PN"BU21"1;
"VSS582"
$PN"BU23"1;
"VSS584"
$PN"BU25"1;
"VSS585"
$PN"BU31"1;
"VSS586"
$PN"BU7"1;
"VSS587"
$PN"BV12"1;
"VSS588"
$PN"BV16"1;
"VSS589"
$PN"BV18"1;
"VSS590"
$PN"BV2"1;
"VSS591"
$PN"BV20"1;
"VSS592"
$PN"BV4"1;
"VSS593"
$PN"BV6"1;
"VSS594"
$PN"BV8"1;
"VSS596"
$PN"BW13"1;
"VSS597"
$PN"BW17"1;
"VSS598"
$PN"BW27"1;
"VSS599"
$PN"BW29"1;
"VSS600"
$PN"BW3"1;
"VSS601"
$PN"BW31"1;
"VSS602"
$PN"BW5"1;
"VSS603"
$PN"BW9"1;
"VSS604"
$PN"BY12"1;
"VSS605"
$PN"BY16"1;
"VSS606"
$PN"BY20"1;
"VSS607"
$PN"BY4"1;
"VSS608"
$PN"BY8"1;
"VSS620"
$PN"CA3"1;
"VSS621"
$PN"CA31"1;
"VSS622"
$PN"CB12"1;
"VSS623"
$PN"CB16"1;
"VSS624"
$PN"CB20"1;
"VSS625"
$PN"CB22"1;
"VSS626"
$PN"CB24"1;
"VSS627"
$PN"CB26"1;
"VSS628"
$PN"CB28"1;
"VSS629"
$PN"CB32"1;
"VSS630"
$PN"CB34"1;
"VSS631"
$PN"CB36"1;
"VSS632"
$PN"CB38"1;
"VSS633"
$PN"CB4"1;
"VSS634"
$PN"CB40"1;
"VSS635"
$PN"CB42"1;
"VSS636"
$PN"CB44"1;
"VSS637"
$PN"CB47"1;
"VSS638"
$PN"CB49"1;
"VSS639"
$PN"CB51"1;
"VSS640"
$PN"CB53"1;
"VSS641"
$PN"CB55"2;
"VSS642"
$PN"CB57"2;
"VSS643"
$PN"CB59"2;
"VSS644"
$PN"CB63"2;
"VSS645"
$PN"CB65"2;
"VSS646"
$PN"CB67"2;
"VSS647"
$PN"CB69"2;
"VSS648"
$PN"CB71"2;
"VSS649"
$PN"CB73"2;
"VSS650"
$PN"CB79"2;
"VSS651"
$PN"CB8"1;
"VSS652"
$PN"CB81"2;
"VSS653"
$PN"CB83"2;
"VSS654"
$PN"CB85"2;
"VSS655"
$PN"CB87"2;
"VSS656"
$PN"CB89"2;
"VSS660"
$PN"CC13"2;
"VSS661"
$PN"CC17"2;
"VSS664"
$PN"CC31"2;
"VSS665"
$PN"CC5"2;
"VSS666"
$PN"CC62"2;
"VSS667"
$PN"CC70"2;
"VSS668"
$PN"CC72"2;
"VSS669"
$PN"CC74"2;
"VSS670"
$PN"CC9"2;
"VSS671"
$PN"CD12"2;
"VSS672"
$PN"CD16"2;
"VSS673"
$PN"CD20"2;
"VSS674"
$PN"CD4"2;
"VSS675"
$PN"CD61"2;
"VSS676"
$PN"CD75"2;
"VSS677"
$PN"CD77"2;
"VSS678"
$PN"CD8"2;
"VSS680"
$PN"CE3"2;
"VSS681"
$PN"CE60"2;
"VSS682"
$PN"CE66"2;
"VSS683"
$PN"CE72"2;
"VSS684"
$PN"CE76"2;
"VSS685"
$PN"CE78"2;
"VSS686"
$PN"CF12"2;
"VSS687"
$PN"CF16"2;
"VSS688"
$PN"CF20"2;
"VSS689"
$PN"CF4"2;
"VSS691"
$PN"CF69"2;
"VSS692"
$PN"CF71"2;
"VSS693"
$PN"CF8"2;
"VSS694"
$PN"CG1"2;
"VSS695"
$PN"CG13"2;
"VSS696"
$PN"CG17"2;
"VSS697"
$PN"CG21"2;
"VSS698"
$PN"CG23"2;
"VSS701"
$PN"CG25"2;
"VSS703"
$PN"CG5"2;
"VSS704"
$PN"CG62"2;
"VSS706"
$PN"CG64"2;
"VSS707"
$PN"CG70"2;
"VSS708"
$PN"CG72"2;
"VSS710"
$PN"CG74"2;
"VSS713"
$PN"CG78"2;
"VSS716"
$PN"CG9"2;
"VSS718"
$PN"CH12"2;
"VSS720"
$PN"CH16"2;
"VSS721"
$PN"CH20"2;
"VSS722"
$PN"CH4"2;
"VSS727"
$PN"CH67"2;
"VSS728"
$PN"CH73"2;
"VSS729"
$PN"CH79"2;
"VSS730"
$PN"CH8"2;
"VSS731"
$PN"CH83"2;
"VSS732"
$PN"CH85"2;
"VSS733"
$PN"CH87"2;
"VSS734"
$PN"CH89"2;
"VSS736"
$PN"CJ60"2;
"VSS737"
$PN"CJ80"2;
"VSS740"
$PN"CK12"2;
"VSS741"
$PN"CK16"2;
"VSS742"
$PN"CK20"2;
"VSS743"
$PN"CK26"2;
"VSS746"
$PN"CK8"2;
%"UNIVERSAL_GND"
"1","(-775,-725)","0","logical_power","I3";
;
CDS_LIB"logical_power"
HDL_POWER"GND";
"A"5;
%"UNIVERSAL_GND"
"1","(-625,-725)","0","logical_power","I4";
;
CDS_LIB"logical_power"
HDL_POWER"GND";
"A"4;
%"UNIVERSAL_GND"
"1","(2275,-725)","0","logical_power","I6";
;
CDS_LIB"logical_power"
HDL_POWER"GND";
"A"3;
%"UNIVERSAL_GND"
"1","(2400,-725)","0","logical_power","I7";
;
CDS_LIB"logical_power"
HDL_POWER"GND";
"A"2;
%"UNIVERSAL_GND"
"1","(5300,-725)","0","logical_power","I9";
;
CDS_LIB"logical_power"
HDL_POWER"GND";
"A"1;
END.
